# T6G (Grand Teton) — schematic netlist excerpt (pin names and nets, part order shuffled) for the footprints in the layout excerpt that follows; sources: Cadence DE-HDL packaged netlist, KiCad conversion of 04192023_DAF0TMB3IC0_F0TG_MB_C_brd_V02_OCP.brd

C2050  Q_CAP  0.1UF 25V 10% X7R  pkg 0402  page 257 : A = P3V3_PDB_AUX_ADC_TIC ; B = GND
R3767  Q_RES  0.002 1% CHIP  pkg 2512LF  page 236 : A = P3V3_E1S_0 ; B = P3V3_E1S_0_R
R552  Q_RES  4.7K 5% CHIP  pkg 0402LF  page 188 : A = P3V3_AUX ; B = PWRGD_P5V_R2

(kicad_pcb
	(version 20260206)
	(generator "pcbnew")
	(generator_version "10.0")
	(general
		(thickness 1.6)
		(legacy_teardrops no)
	)
	(paper "A4")
	(title_block
		(title "04192023_DAF0TMB3IC0_F0TG_MB_C_brd_V02_OCP.brd")
		(comment 1 "Grand Teton / footprints 4795-4797 of 8354")
	)
	(layers
		(0 "F.Cu" signal "TOP")
		(4 "In1.Cu" signal "GND")
		(6 "In2.Cu" signal "IN1")
		(8 "In3.Cu" signal "GND1")
		(10 "In4.Cu" signal "IN2")
		(12 "In5.Cu" signal "GND2")
		(14 "In6.Cu" signal "IN3")
		(16 "In7.Cu" signal "GND3")
		(18 "In8.Cu" signal "VCC")
		(20 "In9.Cu" signal "VCC1")
		(22 "In10.Cu" signal "GND4")
		(24 "In11.Cu" signal "IN4")
		(26 "In12.Cu" signal "GND5")
		(28 "In13.Cu" signal "IN5")
		(30 "In14.Cu" signal "GND6")
		(32 "In15.Cu" signal "IN6")
		(34 "In16.Cu" signal "GND7")
		(2 "B.Cu" signal "BOTTOM")
		(9 "F.Adhes" user "F.Adhesive")
		(11 "B.Adhes" user "B.Adhesive")
		(13 "F.Paste" user "Package Geometry/Pastemask Top")
		(15 "B.Paste" user "Package Geometry/Pastemask Bottom")
		(5 "F.SilkS" user "Ref Des/Silkscreen Top")
		(7 "B.SilkS" user "Ref Des/Silkscreen Bottom")
		(1 "F.Mask" user "Board Geometry/Soldermask Top")
		(3 "B.Mask" user "Board Geometry/Soldermask Bottom")
		(17 "Dwgs.User" user "User.Drawings")
		(19 "Cmts.User" user "User.Comments")
		(21 "Eco1.User" user "User.Eco1")
		(23 "Eco2.User" user "User.Eco2")
		(25 "Edge.Cuts" user "Board Geometry/Outline")
		(27 "Margin" user)
		(31 "F.CrtYd" user "Package Geometry/Place Bound Top")
		(29 "B.CrtYd" user "Package Geometry/Place Bound Bottom")
		(35 "F.Fab" user "Ref Des/Assembly Top")
		(33 "B.Fab" user "Ref Des/Assembly Bottom")
	)
	(footprint ""
		(layer "F.Cu")
		(at 319.940178 -40.652954)
		(property "Reference" "C2050"
			(at 0 0 0)
			(layer "F.SilkS")
			(hide yes)
			(effects
				(font
					(size 1.27 1.27)
				)
			)
		)
		(property "Value" ""
			(at 0 0 0)
			(layer "F.Fab")
			(effects
				(font
					(size 1.27 1.27)
				)
			)
		)
		(duplicate_pad_numbers_are_jumpers no)
		(fp_line
			(start -0.7874 -0.4064)
			(end 0.7874 -0.4064)
			(stroke
				(width 0.1524)
				(type default)
			)
			(layer "F.SilkS")
		)
		(fp_line
			(start -0.7874 0.4064)
			(end -0.7874 -0.4064)
			(stroke
				(width 0.1524)
				(type default)
			)
			(layer "F.SilkS")
		)
		(fp_line
			(start 0.7874 -0.4064)
			(end 0.7874 0.4064)
			(stroke
				(width 0.1524)
				(type default)
			)
			(layer "F.SilkS")
		)
		(fp_line
			(start 0.7874 0.4064)
			(end -0.7874 0.4064)
			(stroke
				(width 0.1524)
				(type default)
			)
			(layer "F.SilkS")
		)
		(fp_line
			(start -0.67945 -0.305054)
			(end -0.12065 -0.305054)
			(stroke
				(width 0.1)
				(type default)
			)
			(layer "F.Fab")
		)
		(fp_line
			(start -0.67945 0.3048)
			(end -0.67945 -0.305054)
			(stroke
				(width 0.1)
				(type default)
			)
			(layer "F.Fab")
		)
		(fp_line
			(start -0.12065 -0.305054)
			(end -0.12065 -0.2794)
			(stroke
				(width 0.1)
				(type default)
			)
			(layer "F.Fab")
		)
		(fp_line
			(start -0.12065 -0.2794)
			(end 0.12065 -0.2794)
			(stroke
				(width 0.1)
				(type default)
			)
			(layer "F.Fab")
		)
		(fp_line
			(start -0.12065 0.2794)
			(end -0.12065 0.3048)
			(stroke
				(width 0.1)
				(type default)
			)
			(layer "F.Fab")
		)
		(fp_line
			(start -0.12065 0.3048)
			(end -0.67945 0.3048)
			(stroke
				(width 0.1)
				(type default)
			)
			(layer "F.Fab")
		)
		(fp_line
			(start 0.120396 0.2794)
			(end -0.12065 0.2794)
			(stroke
				(width 0.1)
				(type default)
			)
			(layer "F.Fab")
		)
		(fp_line
			(start 0.120396 0.3048)
			(end 0.120396 0.2794)
			(stroke
				(width 0.1)
				(type default)
			)
			(layer "F.Fab")
		)
		(fp_line
			(start 0.12065 -0.3048)
			(end 0.67945 -0.3048)
			(stroke
				(width 0.1)
				(type default)
			)
			(layer "F.Fab")
		)
		(fp_line
			(start 0.12065 -0.2794)
			(end 0.12065 -0.3048)
			(stroke
				(width 0.1)
				(type default)
			)
			(layer "F.Fab")
		)
		(fp_line
			(start 0.67945 -0.3048)
			(end 0.67945 0.3048)
			(stroke
				(width 0.1)
				(type default)
			)
			(layer "F.Fab")
		)
		(fp_line
			(start 0.67945 0.3048)
			(end 0.120396 0.3048)
			(stroke
				(width 0.1)
				(type default)
			)
			(layer "F.Fab")
		)
		(pad "1" smd circle
			(at -0.40005 0)
			(size 0 0)
			(layers "F.Cu" "F.Mask" "F.Paste")
			(net "P3V3_PDB_AUX_ADC_TIC")
		)
		(pad "2" smd circle
			(at 0.40005 0)
			(size 0 0)
			(layers "F.Cu" "F.Mask" "F.Paste")
			(net "GND")
		)
	)
	(footprint ""
		(layer "F.Cu")
		(at 161.097976 -129.295652 -90)
		(property "Reference" "R552"
			(at 0 0 270)
			(layer "F.SilkS")
			(hide yes)
			(effects
				(font
					(size 1.27 1.27)
				)
			)
		)
		(property "Value" ""
			(at 0 0 270)
			(layer "F.Fab")
			(effects
				(font
					(size 1.27 1.27)
				)
			)
		)
		(duplicate_pad_numbers_are_jumpers no)
		(fp_line
			(start -0.7874 0.4064)
			(end -0.7874 -0.4064)
			(stroke
				(width 0.1524)
				(type default)
			)
			(layer "F.SilkS")
		)
		(fp_line
			(start 0.7874 0.4064)
			(end -0.7874 0.4064)
			(stroke
				(width 0.1524)
				(type default)
			)
			(layer "F.SilkS")
		)
		(fp_line
			(start -0.7874 -0.4064)
			(end 0.7874 -0.4064)
			(stroke
				(width 0.1524)
				(type default)
			)
			(layer "F.SilkS")
		)
		(fp_line
			(start 0.7874 -0.4064)
			(end 0.7874 0.4064)
			(stroke
				(width 0.1524)
				(type default)
			)
			(layer "F.SilkS")
		)
		(fp_line
			(start -0.67945 0.3048)
			(end -0.67945 -0.305054)
			(stroke
				(width 0.1)
				(type default)
			)
			(layer "F.Fab")
		)
		(fp_line
			(start -0.12065 0.3048)
			(end -0.67945 0.3048)
			(stroke
				(width 0.1)
				(type default)
			)
			(layer "F.Fab")
		)
		(fp_line
			(start 0.120396 0.3048)
			(end 0.120396 0.2794)
			(stroke
				(width 0.1)
				(type default)
			)
			(layer "F.Fab")
		)
		(fp_line
			(start 0.67945 0.3048)
			(end 0.120396 0.3048)
			(stroke
				(width 0.1)
				(type default)
			)
			(layer "F.Fab")
		)
		(fp_line
			(start -0.12065 0.2794)
			(end -0.12065 0.3048)
			(stroke
				(width 0.1)
				(type default)
			)
			(layer "F.Fab")
		)
		(fp_line
			(start 0.120396 0.2794)
			(end -0.12065 0.2794)
			(stroke
				(width 0.1)
				(type default)
			)
			(layer "F.Fab")
		)
		(fp_line
			(start -0.12065 -0.2794)
			(end 0.12065 -0.2794)
			(stroke
				(width 0.1)
				(type default)
			)
			(layer "F.Fab")
		)
		(fp_line
			(start 0.12065 -0.2794)
			(end 0.12065 -0.3048)
			(stroke
				(width 0.1)
				(type default)
			)
			(layer "F.Fab")
		)
		(fp_line
			(start 0.12065 -0.3048)
			(end 0.67945 -0.3048)
			(stroke
				(width 0.1)
				(type default)
			)
			(layer "F.Fab")
		)
		(fp_line
			(start 0.67945 -0.3048)
			(end 0.67945 0.3048)
			(stroke
				(width 0.1)
				(type default)
			)
			(layer "F.Fab")
		)
		(fp_line
			(start -0.67945 -0.305054)
			(end -0.12065 -0.305054)
			(stroke
				(width 0.1)
				(type default)
			)
			(layer "F.Fab")
		)
		(fp_line
			(start -0.12065 -0.305054)
			(end -0.12065 -0.2794)
			(stroke
				(width 0.1)
				(type default)
			)
			(layer "F.Fab")
		)
		(pad "1" smd circle
			(at -0.40005 0 270)
			(size 0 0)
			(layers "F.Cu" "F.Mask" "F.Paste")
			(net "P3V3_AUX")
		)
		(pad "2" smd circle
			(at 0.40005 0 270)
			(size 0 0)
			(layers "F.Cu" "F.Mask" "F.Paste")
			(net "PWRGD_P5V_R2")
		)
	)
	(footprint ""
		(layer "F.Cu")
		(at 224.074482 -57.386982 90)
		(property "Reference" "R3767"
			(at 4.689348 -1.951482 0)
			(unlocked yes)
			(layer "F.SilkS")
			(effects
				(font
					(size 0.7874 0.5842)
					(thickness 0.1524)
				)
				(justify left)
			)
		)
		(property "Value" ""
			(at 0 0 90)
			(layer "F.Fab")
			(effects
				(font
					(size 1.27 1.27)
				)
			)
		)
		(duplicate_pad_numbers_are_jumpers no)
		(fp_line
			(start 3.937508 -1.8796)
			(end -3.937508 -1.8796)
			(stroke
				(width 0.1524)
				(type default)
			)
			(layer "F.SilkS")
		)
		(fp_line
			(start -3.937508 -1.8796)
			(end -3.937508 1.8796)
			(stroke
				(width 0.1524)
				(type default)
			)
			(layer "F.SilkS")
		)
		(fp_line
			(start 3.937508 1.8796)
			(end 3.937508 -1.8796)
			(stroke
				(width 0.1524)
				(type default)
			)
			(layer "F.SilkS")
		)
		(fp_line
			(start -3.937508 1.8796)
			(end 3.937508 1.8796)
			(stroke
				(width 0.1524)
				(type default)
			)
			(layer "F.SilkS")
		)
		(fp_line
			(start 3.275076 -1.674876)
			(end -3.275076 -1.674876)
			(stroke
				(width 0.1)
				(type default)
			)
			(layer "F.Fab")
		)
		(fp_line
			(start -3.275076 -1.674876)
			(end -3.275076 1.674876)
			(stroke
				(width 0.1)
				(type default)
			)
			(layer "F.Fab")
		)
		(fp_line
			(start 3.275076 1.674876)
			(end 3.275076 -1.674876)
			(stroke
				(width 0.1)
				(type default)
			)
			(layer "F.Fab")
		)
		(fp_line
			(start -3.275076 1.674876)
			(end 3.275076 1.674876)
			(stroke
				(width 0.1)
				(type default)
			)
			(layer "F.Fab")
		)
		(pad "1" smd rect
			(at -2.350008 0 90)
			(size 2.921 3.5052)
			(layers "F.Cu" "F.Mask" "F.Paste")
			(net "P3V3_E1S_0")
		)
		(pad "2" smd rect
			(at 2.350008 0 90)
			(size 2.921 3.5052)
			(layers "F.Cu" "F.Mask" "F.Paste")
			(net "P3V3_E1S_0_R")
		)
	)
)
